(kicad_pcb
	(version 20260206)
	(generator "pcbnew")
	(generator_version "10.0")
	(general
		(thickness 1.6)
		(legacy_teardrops no)
	)
	(paper "A4")
	(title_block
		(title "03242023_DA0F0TMBIJ0_F0T_Motherboard_J_brd_V01_OCP.brd")
		(comment 1 "Grand Teton / footprints 5217-5222 of 6105")
	)
	(layers
		(0 "F.Cu" signal "TOP")
		(4 "In1.Cu" signal "GND")
		(6 "In2.Cu" signal "IN1")
		(8 "In3.Cu" signal "GND1")
		(10 "In4.Cu" signal "IN2")
		(12 "In5.Cu" signal "GND2")
		(14 "In6.Cu" signal "IN3")
		(16 "In7.Cu" signal "GND3")
		(18 "In8.Cu" signal "VCC")
		(20 "In9.Cu" signal "VCC1")
		(22 "In10.Cu" signal "GND4")
		(24 "In11.Cu" signal "IN4")
		(26 "In12.Cu" signal "GND5")
		(28 "In13.Cu" signal "IN5")
		(30 "In14.Cu" signal "GND6")
		(32 "In15.Cu" signal "IN6")
		(34 "In16.Cu" signal "GND7")
		(2 "B.Cu" signal "BOTTOM")
		(9 "F.Adhes" user "F.Adhesive")
		(11 "B.Adhes" user "B.Adhesive")
		(13 "F.Paste" user "Package Geometry/Pastemask Top")
		(15 "B.Paste" user "Package Geometry/Pastemask Bottom")
		(5 "F.SilkS" user "Ref Des/Silkscreen Top")
		(7 "B.SilkS" user "Ref Des/Silkscreen Bottom")
		(1 "F.Mask" user "Board Geometry/Soldermask Top")
		(3 "B.Mask" user "Board Geometry/Soldermask Bottom")
		(17 "Dwgs.User" user "User.Drawings")
		(19 "Cmts.User" user "User.Comments")
		(21 "Eco1.User" user "User.Eco1")
		(23 "Eco2.User" user "User.Eco2")
		(25 "Edge.Cuts" user "Board Geometry/Outline")
		(27 "Margin" user)
		(31 "F.CrtYd" user "Package Geometry/Place Bound Top")
		(29 "B.CrtYd" user "Package Geometry/Place Bound Bottom")
		(35 "F.Fab" user "Ref Des/Assembly Top")
		(33 "B.Fab" user "Ref Des/Assembly Bottom")
	)
	(footprint ""
		(layer "B.Cu")
		(at 294.91813 -400.999452 -90)
		(property "Reference" "PR2526"
			(at 0 0 90)
			(layer "B.SilkS")
			(hide yes)
			(effects
				(font
					(size 1.27 1.27)
				)
				(justify mirror)
			)
		)
		(property "Value" ""
			(at 0 0 90)
			(layer "B.Fab")
			(effects
				(font
					(size 1.27 1.27)
				)
				(justify mirror)
			)
		)
		(duplicate_pad_numbers_are_jumpers no)
		(fp_line
			(start -0.7874 0.4064)
			(end 0.7874 0.4064)
			(stroke
				(width 0.1524)
				(type default)
			)
			(layer "B.SilkS")
		)
		(fp_line
			(start 0.7874 0.4064)
			(end 0.7874 -0.4064)
			(stroke
				(width 0.1524)
				(type default)
			)
			(layer "B.SilkS")
		)
		(fp_line
			(start -0.7874 -0.4064)
			(end -0.7874 0.4064)
			(stroke
				(width 0.1524)
				(type default)
			)
			(layer "B.SilkS")
		)
		(fp_line
			(start 0.7874 -0.4064)
			(end -0.7874 -0.4064)
			(stroke
				(width 0.1524)
				(type default)
			)
			(layer "B.SilkS")
		)
		(fp_line
			(start -0.67945 0.3048)
			(end -0.120396 0.3048)
			(stroke
				(width 0.1)
				(type default)
			)
			(layer "B.Fab")
		)
		(fp_line
			(start -0.120396 0.3048)
			(end -0.120396 0.2794)
			(stroke
				(width 0.1)
				(type default)
			)
			(layer "B.Fab")
		)
		(fp_line
			(start 0.12065 0.3048)
			(end 0.67945 0.3048)
			(stroke
				(width 0.1)
				(type default)
			)
			(layer "B.Fab")
		)
		(fp_line
			(start 0.67945 0.3048)
			(end 0.67945 -0.305054)
			(stroke
				(width 0.1)
				(type default)
			)
			(layer "B.Fab")
		)
		(fp_line
			(start -0.120396 0.2794)
			(end 0.12065 0.2794)
			(stroke
				(width 0.1)
				(type default)
			)
			(layer "B.Fab")
		)
		(fp_line
			(start 0.12065 0.2794)
			(end 0.12065 0.3048)
			(stroke
				(width 0.1)
				(type default)
			)
			(layer "B.Fab")
		)
		(fp_line
			(start -0.12065 -0.2794)
			(end -0.12065 -0.3048)
			(stroke
				(width 0.1)
				(type default)
			)
			(layer "B.Fab")
		)
		(fp_line
			(start 0.12065 -0.2794)
			(end -0.12065 -0.2794)
			(stroke
				(width 0.1)
				(type default)
			)
			(layer "B.Fab")
		)
		(fp_line
			(start -0.67945 -0.3048)
			(end -0.67945 0.3048)
			(stroke
				(width 0.1)
				(type default)
			)
			(layer "B.Fab")
		)
		(fp_line
			(start -0.12065 -0.3048)
			(end -0.67945 -0.3048)
			(stroke
				(width 0.1)
				(type default)
			)
			(layer "B.Fab")
		)
		(fp_line
			(start 0.12065 -0.305054)
			(end 0.12065 -0.2794)
			(stroke
				(width 0.1)
				(type default)
			)
			(layer "B.Fab")
		)
		(fp_line
			(start 0.67945 -0.305054)
			(end 0.12065 -0.305054)
			(stroke
				(width 0.1)
				(type default)
			)
			(layer "B.Fab")
		)
		(pad "1" smd circle
			(at 0.40005 0 90)
			(size 0 0)
			(layers "B.Cu" "B.Mask" "B.Paste")
			(net "P12V_HSC_SENSE2_N")
		)
		(pad "2" smd circle
			(at -0.40005 0 90)
			(size 0 0)
			(layers "B.Cu" "B.Mask" "B.Paste")
			(net "P12V_HSC_SENSE2_R3_N")
		)
	)
	(footprint ""
		(layer "B.Cu")
		(at 256.09169 -318.482726 180)
		(property "Reference" "R3881"
			(at 0 0 0)
			(layer "B.SilkS")
			(hide yes)
			(effects
				(font
					(size 1.27 1.27)
				)
				(justify mirror)
			)
		)
		(property "Value" ""
			(at 0 0 0)
			(layer "B.Fab")
			(effects
				(font
					(size 1.27 1.27)
				)
				(justify mirror)
			)
		)
		(duplicate_pad_numbers_are_jumpers no)
		(fp_line
			(start 0.7874 0.4064)
			(end 0.7874 -0.4064)
			(stroke
				(width 0.1524)
				(type default)
			)
			(layer "B.SilkS")
		)
		(fp_line
			(start 0.7874 -0.4064)
			(end -0.7874 -0.4064)
			(stroke
				(width 0.1524)
				(type default)
			)
			(layer "B.SilkS")
		)
		(fp_line
			(start -0.7874 0.4064)
			(end 0.7874 0.4064)
			(stroke
				(width 0.1524)
				(type default)
			)
			(layer "B.SilkS")
		)
		(fp_line
			(start -0.7874 -0.4064)
			(end -0.7874 0.4064)
			(stroke
				(width 0.1524)
				(type default)
			)
			(layer "B.SilkS")
		)
		(fp_line
			(start 0.67945 0.3048)
			(end 0.67945 -0.305054)
			(stroke
				(width 0.1)
				(type default)
			)
			(layer "B.Fab")
		)
		(fp_line
			(start 0.67945 -0.305054)
			(end 0.12065 -0.305054)
			(stroke
				(width 0.1)
				(type default)
			)
			(layer "B.Fab")
		)
		(fp_line
			(start 0.12065 0.3048)
			(end 0.67945 0.3048)
			(stroke
				(width 0.1)
				(type default)
			)
			(layer "B.Fab")
		)
		(fp_line
			(start 0.12065 0.2794)
			(end 0.12065 0.3048)
			(stroke
				(width 0.1)
				(type default)
			)
			(layer "B.Fab")
		)
		(fp_line
			(start 0.12065 -0.2794)
			(end -0.12065 -0.2794)
			(stroke
				(width 0.1)
				(type default)
			)
			(layer "B.Fab")
		)
		(fp_line
			(start 0.12065 -0.305054)
			(end 0.12065 -0.2794)
			(stroke
				(width 0.1)
				(type default)
			)
			(layer "B.Fab")
		)
		(fp_line
			(start -0.120396 0.3048)
			(end -0.120396 0.2794)
			(stroke
				(width 0.1)
				(type default)
			)
			(layer "B.Fab")
		)
		(fp_line
			(start -0.120396 0.2794)
			(end 0.12065 0.2794)
			(stroke
				(width 0.1)
				(type default)
			)
			(layer "B.Fab")
		)
		(fp_line
			(start -0.12065 -0.2794)
			(end -0.12065 -0.3048)
			(stroke
				(width 0.1)
				(type default)
			)
			(layer "B.Fab")
		)
		(fp_line
			(start -0.12065 -0.3048)
			(end -0.67945 -0.3048)
			(stroke
				(width 0.1)
				(type default)
			)
			(layer "B.Fab")
		)
		(fp_line
			(start -0.67945 0.3048)
			(end -0.120396 0.3048)
			(stroke
				(width 0.1)
				(type default)
			)
			(layer "B.Fab")
		)
		(fp_line
			(start -0.67945 -0.3048)
			(end -0.67945 0.3048)
			(stroke
				(width 0.1)
				(type default)
			)
			(layer "B.Fab")
		)
		(pad "1" smd circle
			(at 0.40005 0)
			(size 0 0)
			(layers "B.Cu" "B.Mask" "B.Paste")
			(net "I3C_SPD_DDRABCD_CPU0_LVC1_SCL_6")
		)
		(pad "2" smd circle
			(at -0.40005 0)
			(size 0 0)
			(layers "B.Cu" "B.Mask" "B.Paste")
			(net "I3C_SPD_DDRABCD_CPU0_LVC1_SCL")
		)
	)
	(footprint ""
		(layer "B.Cu")
		(at 353.551998 -56.833516)
		(property "Reference" "R1464"
			(at 0 0 0)
			(layer "B.SilkS")
			(hide yes)
			(effects
				(font
					(size 1.27 1.27)
				)
				(justify mirror)
			)
		)
		(property "Value" ""
			(at 0 0 0)
			(layer "B.Fab")
			(effects
				(font
					(size 1.27 1.27)
				)
				(justify mirror)
			)
		)
		(duplicate_pad_numbers_are_jumpers no)
		(fp_line
			(start -0.7874 -0.4064)
			(end -0.7874 0.4064)
			(stroke
				(width 0.1524)
				(type default)
			)
			(layer "B.SilkS")
		)
		(fp_line
			(start -0.7874 0.4064)
			(end 0.7874 0.4064)
			(stroke
				(width 0.1524)
				(type default)
			)
			(layer "B.SilkS")
		)
		(fp_line
			(start 0.7874 -0.4064)
			(end -0.7874 -0.4064)
			(stroke
				(width 0.1524)
				(type default)
			)
			(layer "B.SilkS")
		)
		(fp_line
			(start 0.7874 0.4064)
			(end 0.7874 -0.4064)
			(stroke
				(width 0.1524)
				(type default)
			)
			(layer "B.SilkS")
		)
		(fp_line
			(start -0.67945 -0.3048)
			(end -0.67945 0.3048)
			(stroke
				(width 0.1)
				(type default)
			)
			(layer "B.Fab")
		)
		(fp_line
			(start -0.67945 0.3048)
			(end -0.120396 0.3048)
			(stroke
				(width 0.1)
				(type default)
			)
			(layer "B.Fab")
		)
		(fp_line
			(start -0.12065 -0.3048)
			(end -0.67945 -0.3048)
			(stroke
				(width 0.1)
				(type default)
			)
			(layer "B.Fab")
		)
		(fp_line
			(start -0.12065 -0.2794)
			(end -0.12065 -0.3048)
			(stroke
				(width 0.1)
				(type default)
			)
			(layer "B.Fab")
		)
		(fp_line
			(start -0.120396 0.2794)
			(end 0.12065 0.2794)
			(stroke
				(width 0.1)
				(type default)
			)
			(layer "B.Fab")
		)
		(fp_line
			(start -0.120396 0.3048)
			(end -0.120396 0.2794)
			(stroke
				(width 0.1)
				(type default)
			)
			(layer "B.Fab")
		)
		(fp_line
			(start 0.12065 -0.305054)
			(end 0.12065 -0.2794)
			(stroke
				(width 0.1)
				(type default)
			)
			(layer "B.Fab")
		)
		(fp_line
			(start 0.12065 -0.2794)
			(end -0.12065 -0.2794)
			(stroke
				(width 0.1)
				(type default)
			)
			(layer "B.Fab")
		)
		(fp_line
			(start 0.12065 0.2794)
			(end 0.12065 0.3048)
			(stroke
				(width 0.1)
				(type default)
			)
			(layer "B.Fab")
		)
		(fp_line
			(start 0.12065 0.3048)
			(end 0.67945 0.3048)
			(stroke
				(width 0.1)
				(type default)
			)
			(layer "B.Fab")
		)
		(fp_line
			(start 0.67945 -0.305054)
			(end 0.12065 -0.305054)
			(stroke
				(width 0.1)
				(type default)
			)
			(layer "B.Fab")
		)
		(fp_line
			(start 0.67945 0.3048)
			(end 0.67945 -0.305054)
			(stroke
				(width 0.1)
				(type default)
			)
			(layer "B.Fab")
		)
		(pad "1" smd circle
			(at 0.40005 0 180)
			(size 0 0)
			(layers "B.Cu" "B.Mask" "B.Paste")
			(net "P1V8_PCH_AUX")
		)
		(pad "2" smd circle
			(at -0.40005 0 180)
			(size 0 0)
			(layers "B.Cu" "B.Mask" "B.Paste")
			(net "P1V8_PCH_PLL_AUX")
		)
	)
	(footprint ""
		(layer "B.Cu")
		(at 407.91257 -175.986948 180)
		(property "Reference" "PC203_P0_2"
			(at 0 0 0)
			(layer "B.SilkS")
			(hide yes)
			(effects
				(font
					(size 1.27 1.27)
				)
				(justify mirror)
			)
		)
		(property "Value" ""
			(at 0 0 0)
			(layer "B.Fab")
			(effects
				(font
					(size 1.27 1.27)
				)
				(justify mirror)
			)
		)
		(duplicate_pad_numbers_are_jumpers no)
		(fp_line
			(start 1.524 0.762)
			(end 1.524 -0.762)
			(stroke
				(width 0.1524)
				(type default)
			)
			(layer "B.SilkS")
		)
		(fp_line
			(start 1.524 -0.762)
			(end -1.524 -0.762)
			(stroke
				(width 0.1524)
				(type default)
			)
			(layer "B.SilkS")
		)
		(fp_line
			(start -1.524 0.762)
			(end 1.524 0.762)
			(stroke
				(width 0.1524)
				(type default)
			)
			(layer "B.SilkS")
		)
		(fp_line
			(start -1.524 -0.762)
			(end -1.524 0.762)
			(stroke
				(width 0.1524)
				(type default)
			)
			(layer "B.SilkS")
		)
		(fp_line
			(start 1.1049 0.724916)
			(end -1.1049 0.724916)
			(stroke
				(width 0.1)
				(type default)
			)
			(layer "B.Fab")
		)
		(fp_line
			(start 1.1049 -0.724916)
			(end 1.1049 0.724916)
			(stroke
				(width 0.1)
				(type default)
			)
			(layer "B.Fab")
		)
		(fp_line
			(start -1.1049 0.724916)
			(end -1.1049 -0.724916)
			(stroke
				(width 0.1)
				(type default)
			)
			(layer "B.Fab")
		)
		(fp_line
			(start -1.1049 -0.724916)
			(end 1.1049 -0.724916)
			(stroke
				(width 0.1)
				(type default)
			)
			(layer "B.Fab")
		)
		(pad "1" smd rect
			(at 0.889 0 180)
			(size 1.016 1.27)
			(layers "B.Cu" "B.Mask" "B.Paste")
			(net "PVCCINFAON_CPU0")
		)
		(pad "2" smd rect
			(at -0.889 0 180)
			(size 1.016 1.27)
			(layers "B.Cu" "B.Mask" "B.Paste")
			(net "GND")
		)
	)
	(footprint ""
		(layer "B.Cu")
		(at 164.64788 -109.565948 180)
		(property "Reference" "R2664"
			(at 0 0 0)
			(layer "B.SilkS")
			(hide yes)
			(effects
				(font
					(size 1.27 1.27)
				)
				(justify mirror)
			)
		)
		(property "Value" ""
			(at 0 0 0)
			(layer "B.Fab")
			(effects
				(font
					(size 1.27 1.27)
				)
				(justify mirror)
			)
		)
		(duplicate_pad_numbers_are_jumpers no)
		(fp_line
			(start 0.7874 0.4064)
			(end 0.7874 -0.4064)
			(stroke
				(width 0.1524)
				(type default)
			)
			(layer "B.SilkS")
		)
		(fp_line
			(start 0.7874 -0.4064)
			(end -0.7874 -0.4064)
			(stroke
				(width 0.1524)
				(type default)
			)
			(layer "B.SilkS")
		)
		(fp_line
			(start -0.7874 0.4064)
			(end 0.7874 0.4064)
			(stroke
				(width 0.1524)
				(type default)
			)
			(layer "B.SilkS")
		)
		(fp_line
			(start -0.7874 -0.4064)
			(end -0.7874 0.4064)
			(stroke
				(width 0.1524)
				(type default)
			)
			(layer "B.SilkS")
		)
		(fp_line
			(start 0.67945 0.3048)
			(end 0.67945 -0.305054)
			(stroke
				(width 0.1)
				(type default)
			)
			(layer "B.Fab")
		)
		(fp_line
			(start 0.67945 -0.305054)
			(end 0.12065 -0.305054)
			(stroke
				(width 0.1)
				(type default)
			)
			(layer "B.Fab")
		)
		(fp_line
			(start 0.12065 0.3048)
			(end 0.67945 0.3048)
			(stroke
				(width 0.1)
				(type default)
			)
			(layer "B.Fab")
		)
		(fp_line
			(start 0.12065 0.2794)
			(end 0.12065 0.3048)
			(stroke
				(width 0.1)
				(type default)
			)
			(layer "B.Fab")
		)
		(fp_line
			(start 0.12065 -0.2794)
			(end -0.12065 -0.2794)
			(stroke
				(width 0.1)
				(type default)
			)
			(layer "B.Fab")
		)
		(fp_line
			(start 0.12065 -0.305054)
			(end 0.12065 -0.2794)
			(stroke
				(width 0.1)
				(type default)
			)
			(layer "B.Fab")
		)
		(fp_line
			(start -0.120396 0.3048)
			(end -0.120396 0.2794)
			(stroke
				(width 0.1)
				(type default)
			)
			(layer "B.Fab")
		)
		(fp_line
			(start -0.120396 0.2794)
			(end 0.12065 0.2794)
			(stroke
				(width 0.1)
				(type default)
			)
			(layer "B.Fab")
		)
		(fp_line
			(start -0.12065 -0.2794)
			(end -0.12065 -0.3048)
			(stroke
				(width 0.1)
				(type default)
			)
			(layer "B.Fab")
		)
		(fp_line
			(start -0.12065 -0.3048)
			(end -0.67945 -0.3048)
			(stroke
				(width 0.1)
				(type default)
			)
			(layer "B.Fab")
		)
		(fp_line
			(start -0.67945 0.3048)
			(end -0.120396 0.3048)
			(stroke
				(width 0.1)
				(type default)
			)
			(layer "B.Fab")
		)
		(fp_line
			(start -0.67945 -0.3048)
			(end -0.67945 0.3048)
			(stroke
				(width 0.1)
				(type default)
			)
			(layer "B.Fab")
		)
		(pad "1" smd circle
			(at 0.40005 0)
			(size 0 0)
			(layers "B.Cu" "B.Mask" "B.Paste")
			(net "FM_GPU_PWRGD_ISO")
		)
		(pad "2" smd circle
			(at -0.40005 0)
			(size 0 0)
			(layers "B.Cu" "B.Mask" "B.Paste")
			(net "FM_GPU_PWRGD_ISO_R")
		)
	)
	(footprint ""
		(layer "B.Cu")
		(at 14.616176 -101.217984 90)
		(property "Reference" "C2031"
			(at 0 0 90)
			(layer "B.SilkS")
			(hide yes)
			(effects
				(font
					(size 1.27 1.27)
				)
				(justify mirror)
			)
		)
		(property "Value" ""
			(at 0 0 90)
			(layer "B.Fab")
			(effects
				(font
					(size 1.27 1.27)
				)
				(justify mirror)
			)
		)
		(duplicate_pad_numbers_are_jumpers no)
		(fp_line
			(start 0.7874 -0.4064)
			(end -0.7874 -0.4064)
			(stroke
				(width 0.1524)
				(type default)
			)
			(layer "B.SilkS")
		)
		(fp_line
			(start -0.7874 -0.4064)
			(end -0.7874 0.4064)
			(stroke
				(width 0.1524)
				(type default)
			)
			(layer "B.SilkS")
		)
		(fp_line
			(start 0.7874 0.4064)
			(end 0.7874 -0.4064)
			(stroke
				(width 0.1524)
				(type default)
			)
			(layer "B.SilkS")
		)
		(fp_line
			(start -0.7874 0.4064)
			(end 0.7874 0.4064)
			(stroke
				(width 0.1524)
				(type default)
			)
			(layer "B.SilkS")
		)
		(fp_line
			(start 0.67945 -0.305054)
			(end 0.12065 -0.305054)
			(stroke
				(width 0.1)
				(type default)
			)
			(layer "B.Fab")
		)
		(fp_line
			(start 0.12065 -0.305054)
			(end 0.12065 -0.2794)
			(stroke
				(width 0.1)
				(type default)
			)
			(layer "B.Fab")
		)
		(fp_line
			(start -0.12065 -0.3048)
			(end -0.67945 -0.3048)
			(stroke
				(width 0.1)
				(type default)
			)
			(layer "B.Fab")
		)
		(fp_line
			(start -0.67945 -0.3048)
			(end -0.67945 0.3048)
			(stroke
				(width 0.1)
				(type default)
			)
			(layer "B.Fab")
		)
		(fp_line
			(start 0.12065 -0.2794)
			(end -0.12065 -0.2794)
			(stroke
				(width 0.1)
				(type default)
			)
			(layer "B.Fab")
		)
		(fp_line
			(start -0.12065 -0.2794)
			(end -0.12065 -0.3048)
			(stroke
				(width 0.1)
				(type default)
			)
			(layer "B.Fab")
		)
		(fp_line
			(start 0.12065 0.2794)
			(end 0.12065 0.3048)
			(stroke
				(width 0.1)
				(type default)
			)
			(layer "B.Fab")
		)
		(fp_line
			(start -0.120396 0.2794)
			(end 0.12065 0.2794)
			(stroke
				(width 0.1)
				(type default)
			)
			(layer "B.Fab")
		)
		(fp_line
			(start 0.67945 0.3048)
			(end 0.67945 -0.305054)
			(stroke
				(width 0.1)
				(type default)
			)
			(layer "B.Fab")
		)
		(fp_line
			(start 0.12065 0.3048)
			(end 0.67945 0.3048)
			(stroke
				(width 0.1)
				(type default)
			)
			(layer "B.Fab")
		)
		(fp_line
			(start -0.120396 0.3048)
			(end -0.120396 0.2794)
			(stroke
				(width 0.1)
				(type default)
			)
			(layer "B.Fab")
		)
		(fp_line
			(start -0.67945 0.3048)
			(end -0.120396 0.3048)
			(stroke
				(width 0.1)
				(type default)
			)
			(layer "B.Fab")
		)
		(pad "1" smd circle
			(at 0.40005 0 270)
			(size 0 0)
			(layers "B.Cu" "B.Mask" "B.Paste")
			(net "P3V3_AUX_USB_HUB")
		)
		(pad "2" smd circle
			(at -0.40005 0 270)
			(size 0 0)
			(layers "B.Cu" "B.Mask" "B.Paste")
			(net "GND")
		)
	)
)
